# T6G (Grand Teton) — schematic netlist excerpt (pin names and nets, part order shuffled) for the footprints in the layout excerpt that follows; sources: Cadence DE-HDL packaged netlist, KiCad conversion of 04192023_DAF0TMB3IC0_F0TG_MB_C_brd_V02_OCP.brd

R451  Q_RES  4.7K 5% CHIP  pkg 0402LF  page 28 : A = CPU0_SPD_HOST_CTRL_N ; B = PVDD18_S5_P0
PR342  Q_RES  1K 1% CHIP  pkg 0402LF  page 218 : A = PVDDCR_CPU1_P1 ; B = GND

(kicad_pcb
	(version 20260206)
	(generator "pcbnew")
	(generator_version "10.0")
	(general
		(thickness 1.6)
		(legacy_teardrops no)
	)
	(paper "A4")
	(title_block
		(title "04192023_DAF0TMB3IC0_F0TG_MB_C_brd_V02_OCP.brd")
		(comment 1 "Grand Teton / footprints 7528-7529 of 8354")
	)
	(layers
		(0 "F.Cu" signal "TOP")
		(4 "In1.Cu" signal "GND")
		(6 "In2.Cu" signal "IN1")
		(8 "In3.Cu" signal "GND1")
		(10 "In4.Cu" signal "IN2")
		(12 "In5.Cu" signal "GND2")
		(14 "In6.Cu" signal "IN3")
		(16 "In7.Cu" signal "GND3")
		(18 "In8.Cu" signal "VCC")
		(20 "In9.Cu" signal "VCC1")
		(22 "In10.Cu" signal "GND4")
		(24 "In11.Cu" signal "IN4")
		(26 "In12.Cu" signal "GND5")
		(28 "In13.Cu" signal "IN5")
		(30 "In14.Cu" signal "GND6")
		(32 "In15.Cu" signal "IN6")
		(34 "In16.Cu" signal "GND7")
		(2 "B.Cu" signal "BOTTOM")
		(9 "F.Adhes" user "F.Adhesive")
		(11 "B.Adhes" user "B.Adhesive")
		(13 "F.Paste" user "Package Geometry/Pastemask Top")
		(15 "B.Paste" user "Package Geometry/Pastemask Bottom")
		(5 "F.SilkS" user "Ref Des/Silkscreen Top")
		(7 "B.SilkS" user "Ref Des/Silkscreen Bottom")
		(1 "F.Mask" user "Board Geometry/Soldermask Top")
		(3 "B.Mask" user "Board Geometry/Soldermask Bottom")
		(17 "Dwgs.User" user "User.Drawings")
		(19 "Cmts.User" user "User.Comments")
		(21 "Eco1.User" user "User.Eco1")
		(23 "Eco2.User" user "User.Eco2")
		(25 "Edge.Cuts" user "Board Geometry/Outline")
		(27 "Margin" user)
		(31 "F.CrtYd" user "Package Geometry/Place Bound Top")
		(29 "B.CrtYd" user "Package Geometry/Place Bound Bottom")
		(35 "F.Fab" user "Ref Des/Assembly Top")
		(33 "B.Fab" user "Ref Des/Assembly Bottom")
	)
	(footprint ""
		(layer "B.Cu")
		(at 404.584408 -330.849732 90)
		(property "Reference" "R451"
			(at 0 0 90)
			(layer "B.SilkS")
			(hide yes)
			(effects
				(font
					(size 1.27 1.27)
				)
				(justify mirror)
			)
		)
		(property "Value" ""
			(at 0 0 90)
			(layer "B.Fab")
			(effects
				(font
					(size 1.27 1.27)
				)
				(justify mirror)
			)
		)
		(duplicate_pad_numbers_are_jumpers no)
		(fp_line
			(start 0.7874 -0.4064)
			(end -0.7874 -0.4064)
			(stroke
				(width 0.1524)
				(type default)
			)
			(layer "B.SilkS")
		)
		(fp_line
			(start -0.7874 -0.4064)
			(end -0.7874 0.4064)
			(stroke
				(width 0.1524)
				(type default)
			)
			(layer "B.SilkS")
		)
		(fp_line
			(start 0.7874 0.4064)
			(end 0.7874 -0.4064)
			(stroke
				(width 0.1524)
				(type default)
			)
			(layer "B.SilkS")
		)
		(fp_line
			(start -0.7874 0.4064)
			(end 0.7874 0.4064)
			(stroke
				(width 0.1524)
				(type default)
			)
			(layer "B.SilkS")
		)
		(fp_line
			(start 0.67945 -0.305054)
			(end 0.12065 -0.305054)
			(stroke
				(width 0.1)
				(type default)
			)
			(layer "B.Fab")
		)
		(fp_line
			(start 0.12065 -0.305054)
			(end 0.12065 -0.2794)
			(stroke
				(width 0.1)
				(type default)
			)
			(layer "B.Fab")
		)
		(fp_line
			(start -0.12065 -0.3048)
			(end -0.67945 -0.3048)
			(stroke
				(width 0.1)
				(type default)
			)
			(layer "B.Fab")
		)
		(fp_line
			(start -0.67945 -0.3048)
			(end -0.67945 0.3048)
			(stroke
				(width 0.1)
				(type default)
			)
			(layer "B.Fab")
		)
		(fp_line
			(start 0.12065 -0.2794)
			(end -0.12065 -0.2794)
			(stroke
				(width 0.1)
				(type default)
			)
			(layer "B.Fab")
		)
		(fp_line
			(start -0.12065 -0.2794)
			(end -0.12065 -0.3048)
			(stroke
				(width 0.1)
				(type default)
			)
			(layer "B.Fab")
		)
		(fp_line
			(start 0.12065 0.2794)
			(end 0.12065 0.3048)
			(stroke
				(width 0.1)
				(type default)
			)
			(layer "B.Fab")
		)
		(fp_line
			(start -0.120396 0.2794)
			(end 0.12065 0.2794)
			(stroke
				(width 0.1)
				(type default)
			)
			(layer "B.Fab")
		)
		(fp_line
			(start 0.67945 0.3048)
			(end 0.67945 -0.305054)
			(stroke
				(width 0.1)
				(type default)
			)
			(layer "B.Fab")
		)
		(fp_line
			(start 0.12065 0.3048)
			(end 0.67945 0.3048)
			(stroke
				(width 0.1)
				(type default)
			)
			(layer "B.Fab")
		)
		(fp_line
			(start -0.120396 0.3048)
			(end -0.120396 0.2794)
			(stroke
				(width 0.1)
				(type default)
			)
			(layer "B.Fab")
		)
		(fp_line
			(start -0.67945 0.3048)
			(end -0.120396 0.3048)
			(stroke
				(width 0.1)
				(type default)
			)
			(layer "B.Fab")
		)
		(pad "1" smd circle
			(at 0.40005 0 270)
			(size 0 0)
			(layers "B.Cu" "B.Mask" "B.Paste")
			(net "CPU0_SPD_HOST_CTRL_N")
		)
		(pad "2" smd circle
			(at -0.40005 0 270)
			(size 0 0)
			(layers "B.Cu" "B.Mask" "B.Paste")
			(net "PVDD18_S5_P0")
		)
	)
	(footprint ""
		(layer "B.Cu")
		(at 109.395514 -331.404976 -90)
		(property "Reference" "PR342"
			(at 0 0 90)
			(layer "B.SilkS")
			(hide yes)
			(effects
				(font
					(size 1.27 1.27)
				)
				(justify mirror)
			)
		)
		(property "Value" ""
			(at 0 0 90)
			(layer "B.Fab")
			(effects
				(font
					(size 1.27 1.27)
				)
				(justify mirror)
			)
		)
		(duplicate_pad_numbers_are_jumpers no)
		(fp_line
			(start -0.7874 0.4064)
			(end 0.7874 0.4064)
			(stroke
				(width 0.1524)
				(type default)
			)
			(layer "B.SilkS")
		)
		(fp_line
			(start 0.7874 0.4064)
			(end 0.7874 -0.4064)
			(stroke
				(width 0.1524)
				(type default)
			)
			(layer "B.SilkS")
		)
		(fp_line
			(start -0.7874 -0.4064)
			(end -0.7874 0.4064)
			(stroke
				(width 0.1524)
				(type default)
			)
			(layer "B.SilkS")
		)
		(fp_line
			(start 0.7874 -0.4064)
			(end -0.7874 -0.4064)
			(stroke
				(width 0.1524)
				(type default)
			)
			(layer "B.SilkS")
		)
		(fp_line
			(start -0.67945 0.3048)
			(end -0.120396 0.3048)
			(stroke
				(width 0.1)
				(type default)
			)
			(layer "B.Fab")
		)
		(fp_line
			(start -0.120396 0.3048)
			(end -0.120396 0.2794)
			(stroke
				(width 0.1)
				(type default)
			)
			(layer "B.Fab")
		)
		(fp_line
			(start 0.12065 0.3048)
			(end 0.67945 0.3048)
			(stroke
				(width 0.1)
				(type default)
			)
			(layer "B.Fab")
		)
		(fp_line
			(start 0.67945 0.3048)
			(end 0.67945 -0.305054)
			(stroke
				(width 0.1)
				(type default)
			)
			(layer "B.Fab")
		)
		(fp_line
			(start -0.120396 0.2794)
			(end 0.12065 0.2794)
			(stroke
				(width 0.1)
				(type default)
			)
			(layer "B.Fab")
		)
		(fp_line
			(start 0.12065 0.2794)
			(end 0.12065 0.3048)
			(stroke
				(width 0.1)
				(type default)
			)
			(layer "B.Fab")
		)
		(fp_line
			(start -0.12065 -0.2794)
			(end -0.12065 -0.3048)
			(stroke
				(width 0.1)
				(type default)
			)
			(layer "B.Fab")
		)
		(fp_line
			(start 0.12065 -0.2794)
			(end -0.12065 -0.2794)
			(stroke
				(width 0.1)
				(type default)
			)
			(layer "B.Fab")
		)
		(fp_line
			(start -0.67945 -0.3048)
			(end -0.67945 0.3048)
			(stroke
				(width 0.1)
				(type default)
			)
			(layer "B.Fab")
		)
		(fp_line
			(start -0.12065 -0.3048)
			(end -0.67945 -0.3048)
			(stroke
				(width 0.1)
				(type default)
			)
			(layer "B.Fab")
		)
		(fp_line
			(start 0.12065 -0.305054)
			(end 0.12065 -0.2794)
			(stroke
				(width 0.1)
				(type default)
			)
			(layer "B.Fab")
		)
		(fp_line
			(start 0.67945 -0.305054)
			(end 0.12065 -0.305054)
			(stroke
				(width 0.1)
				(type default)
			)
			(layer "B.Fab")
		)
		(pad "1" smd circle
			(at 0.40005 0 90)
			(size 0 0)
			(layers "B.Cu" "B.Mask" "B.Paste")
			(net "PVDDCR_CPU1_P1")
		)
		(pad "2" smd circle
			(at -0.40005 0 90)
			(size 0 0)
			(layers "B.Cu" "B.Mask" "B.Paste")
			(net "GND")
		)
	)
)
